(kicad_pcb
	(version 20260206)
	(generator "pcbnew")
	(generator_version "10.0")
	(general
		(thickness 1.6)
		(legacy_teardrops no)
	)
	(paper "A4")
	(title_block
		(title "Bryce Canyon_F.DPB_16315-1-OCP.brd")
		(comment 1 "Bryce Canyon / footprints 1239-1245 of 2223")
	)
	(layers
		(0 "F.Cu" signal "TOP")
		(4 "In1.Cu" signal "L2GND")
		(6 "In2.Cu" signal "L3")
		(8 "In3.Cu" signal "L4GND")
		(10 "In4.Cu" signal "L5")
		(12 "In5.Cu" signal "L6VCC")
		(14 "In6.Cu" signal "L7VCC")
		(16 "In7.Cu" signal "L8")
		(18 "In8.Cu" signal "L9GND")
		(20 "In9.Cu" signal "L10")
		(22 "In10.Cu" signal "L11GND")
		(2 "B.Cu" signal "BOTTOM")
		(9 "F.Adhes" user "F.Adhesive")
		(11 "B.Adhes" user "B.Adhesive")
		(13 "F.Paste" user "Package Geometry/Pastemask Top")
		(15 "B.Paste" user "Package Geometry/Pastemask Bottom")
		(5 "F.SilkS" user "Ref Des/Silkscreen Top")
		(7 "B.SilkS" user "Ref Des/Silkscreen Bottom")
		(1 "F.Mask" user "Board Geometry/Soldermask Top")
		(3 "B.Mask" user "Board Geometry/Soldermask Bottom")
		(17 "Dwgs.User" user "User.Drawings")
		(19 "Cmts.User" user "User.Comments")
		(21 "Eco1.User" user "User.Eco1")
		(23 "Eco2.User" user "User.Eco2")
		(25 "Edge.Cuts" user "Board Geometry/Outline")
		(27 "Margin" user)
		(31 "F.CrtYd" user "Package Geometry/Place Bound Top")
		(29 "B.CrtYd" user "Package Geometry/Place Bound Bottom")
		(35 "F.Fab" user "Ref Des/Assembly Top")
		(33 "B.Fab" user "Ref Des/Assembly Bottom")
	)
	(footprint ""
		(layer "F.Cu")
		(at 482.489002 -47.749968 -90)
		(property "Reference" "VIA29"
			(at 0 0 270)
			(layer "F.SilkS")
			(hide yes)
			(effects
				(font
					(size 1.27 1.27)
				)
			)
		)
		(property "Value" "100OHM-8L-1D6MM-L18L16-GP"
			(at -3.7211 -4.5085 270)
			(unlocked yes)
			(layer "F.Fab")
			(hide yes)
			(effects
				(font
					(size 1.016 1.016)
					(thickness 0.1524)
				)
			)
		)
		(property "Device Type" "VIA-PCIE-4P-394076"
			(at -3.7211 -6.0325 270)
			(unlocked yes)
			(layer "F.Fab")
			(hide yes)
			(effects
				(font
					(size 1.016 1.016)
					(thickness 0.1524)
				)
			)
		)
		(duplicate_pad_numbers_are_jumpers no)
		(fp_rect
			(start -1.9685 0.381)
			(end 1.9685 -0.381)
			(stroke
				(width 0)
				(type default)
			)
			(fill no)
			(layer "F.CrtYd")
		)
		(fp_rect
			(start -1.9685 0.381)
			(end 1.9685 -0.381)
			(stroke
				(width 0)
				(type default)
			)
			(fill no)
			(layer "F.Fab")
		)
		(pad "1" thru_hole circle
			(at -1.5875 0 270)
			(size 0.508 0.508)
			(drill 0.254)
			(layers "*.Cu" "*.Mask")
			(remove_unused_layers no)
			(net "GND")
			(clearance 0.127)
			(thermal_gap 0.127)
		)
		(pad "2" thru_hole circle
			(at -0.5715 0 270)
			(size 0.508 0.508)
			(drill 0.254)
			(layers "*.Cu" "*.Mask")
			(remove_unused_layers no)
			(net "PHY_DRV_A_TO_SCC_A_35_DP")
			(clearance 0.127)
			(thermal_gap 0.127)
		)
		(pad "3" thru_hole circle
			(at 0.5715 0 270)
			(size 0.508 0.508)
			(drill 0.254)
			(layers "*.Cu" "*.Mask")
			(remove_unused_layers no)
			(net "PHY_DRV_A_TO_SCC_A_35_DN")
			(clearance 0.127)
			(thermal_gap 0.127)
		)
		(pad "4" thru_hole circle
			(at 1.5875 0 270)
			(size 0.508 0.508)
			(drill 0.254)
			(layers "*.Cu" "*.Mask")
			(remove_unused_layers no)
			(net "GND")
			(clearance 0.127)
			(thermal_gap 0.127)
		)
	)
	(footprint ""
		(layer "F.Cu")
		(at 191.135 -294.767 180)
		(property "Reference" "R249"
			(at 0 0 180)
			(layer "F.SilkS")
			(hide yes)
			(effects
				(font
					(size 1.27 1.27)
				)
			)
		)
		(property "Value" "220R3F-1-GP"
			(at -0.0254 -2.5146 180)
			(unlocked yes)
			(layer "F.Fab")
			(hide yes)
			(effects
				(font
					(size 1.016 1.016)
					(thickness 0.1524)
				)
			)
		)
		(property "Device Type" "R603H22"
			(at -0.0254 -4.0386 180)
			(unlocked yes)
			(layer "F.Fab")
			(hide yes)
			(effects
				(font
					(size 1.016 1.016)
					(thickness 0.1524)
				)
			)
		)
		(duplicate_pad_numbers_are_jumpers no)
		(fp_line
			(start 0.2032 0)
			(end 0.4826 0)
			(stroke
				(width 0.2032)
				(type default)
			)
			(layer "F.SilkS")
		)
		(fp_line
			(start -0.4826 0)
			(end -0.2032 0)
			(stroke
				(width 0.2032)
				(type default)
			)
			(layer "F.SilkS")
		)
		(fp_rect
			(start -0.5842 1.3335)
			(end 0.5842 -1.3335)
			(stroke
				(width 0)
				(type default)
			)
			(fill no)
			(layer "F.CrtYd")
		)
		(fp_rect
			(start -0.5842 1.3335)
			(end 0.5842 -1.3335)
			(stroke
				(width 0)
				(type default)
			)
			(fill no)
			(layer "F.Fab")
		)
		(pad "1" smd custom
			(at 0 -0.762 180)
			(size 0.2159 0.2159)
			(layers "F.Cu" "F.Mask" "F.Paste")
			(net "HDD_PRSNT_5")
			(options
				(clearance outline)
				(anchor circle)
			)
			(primitives
				(gr_poly
					(pts
						(arc
							(start -0.3302 -0.4318)
							(mid -0.402042 -0.402042)
							(end -0.4318 -0.3302)
						)
						(arc
							(start -0.4318 0.3302)
							(mid -0.402042 0.402042)
							(end -0.3302 0.4318)
						)
						(arc
							(start 0.3302 0.4318)
							(mid 0.402042 0.402042)
							(end 0.4318 0.3302)
						)
						(arc
							(start 0.4318 -0.3302)
							(mid 0.402042 -0.402042)
							(end 0.3302 -0.4318)
						)
					)
					(width 0)
					(fill yes)
				)
			)
		)
		(pad "2" smd custom
			(at 0 0.762 180)
			(size 0.2159 0.2159)
			(layers "F.Cu" "F.Mask" "F.Paste")
			(net "DRIVE_A_5_INS")
			(options
				(clearance outline)
				(anchor circle)
			)
			(primitives
				(gr_poly
					(pts
						(arc
							(start -0.3302 -0.4318)
							(mid -0.402042 -0.402042)
							(end -0.4318 -0.3302)
						)
						(arc
							(start -0.4318 0.3302)
							(mid -0.402042 0.402042)
							(end -0.3302 0.4318)
						)
						(arc
							(start 0.3302 0.4318)
							(mid 0.402042 0.402042)
							(end 0.4318 0.3302)
						)
						(arc
							(start 0.4318 -0.3302)
							(mid 0.402042 -0.402042)
							(end 0.3302 -0.4318)
						)
					)
					(width 0)
					(fill yes)
				)
			)
		)
	)
	(footprint ""
		(layer "F.Cu")
		(at 114.725196 -282.695142 -90)
		(property "Reference" "R214"
			(at 0 0 270)
			(layer "F.SilkS")
			(hide yes)
			(effects
				(font
					(size 1.27 1.27)
				)
			)
		)
		(property "Value" "300KR2F-GP"
			(at 0.064008 -3.993896 270)
			(unlocked yes)
			(layer "F.Fab")
			(hide yes)
			(effects
				(font
					(size 1.016 1.016)
					(thickness 0.1524)
				)
			)
		)
		(property "Device Type" "R402H16"
			(at 0.064008 -5.517896 270)
			(unlocked yes)
			(layer "F.Fab")
			(hide yes)
			(effects
				(font
					(size 1.016 1.016)
					(thickness 0.1524)
				)
			)
		)
		(duplicate_pad_numbers_are_jumpers no)
		(fp_line
			(start -0.508 -0.9398)
			(end -0.508 0.9398)
			(stroke
				(width 0.1524)
				(type default)
			)
			(layer "F.SilkS")
		)
		(fp_line
			(start 0.508 -0.9398)
			(end -0.508 -0.9398)
			(stroke
				(width 0.1524)
				(type default)
			)
			(layer "F.SilkS")
		)
		(fp_rect
			(start -0.508 0.9398)
			(end 0.508 -0.9398)
			(stroke
				(width 0)
				(type default)
			)
			(fill no)
			(layer "F.CrtYd")
		)
		(fp_rect
			(start -0.508 0.9398)
			(end 0.508 -0.9398)
			(stroke
				(width 0)
				(type default)
			)
			(fill no)
			(layer "F.Fab")
		)
		(pad "1" smd custom
			(at 0 -0.4445 270)
			(size 0.1397 0.1397)
			(layers "F.Cu" "F.Mask" "F.Paste")
			(net "SW_HDD_N3")
			(options
				(clearance outline)
				(anchor circle)
			)
			(primitives
				(gr_poly
					(pts
						(arc
							(start -0.1778 -0.2794)
							(mid -0.249642 -0.249642)
							(end -0.2794 -0.1778)
						)
						(arc
							(start -0.2794 0.1778)
							(mid -0.249642 0.249642)
							(end -0.1778 0.2794)
						)
						(arc
							(start 0.1778 0.2794)
							(mid 0.249642 0.249642)
							(end 0.2794 0.1778)
						)
						(arc
							(start 0.2794 -0.1778)
							(mid 0.249642 -0.249642)
							(end 0.1778 -0.2794)
						)
					)
					(width 0)
					(fill yes)
				)
			)
		)
		(pad "2" smd custom
			(at 0 0.4445 270)
			(size 0.1397 0.1397)
			(layers "F.Cu" "F.Mask" "F.Paste")
			(net "P12V_A")
			(options
				(clearance outline)
				(anchor circle)
			)
			(primitives
				(gr_poly
					(pts
						(arc
							(start -0.1778 -0.2794)
							(mid -0.249642 -0.249642)
							(end -0.2794 -0.1778)
						)
						(arc
							(start -0.2794 0.1778)
							(mid -0.249642 0.249642)
							(end -0.1778 0.2794)
						)
						(arc
							(start 0.1778 0.2794)
							(mid 0.249642 0.249642)
							(end 0.2794 0.1778)
						)
						(arc
							(start 0.2794 -0.1778)
							(mid 0.249642 -0.249642)
							(end 0.1778 -0.2794)
						)
					)
					(width 0)
					(fill yes)
				)
			)
		)
	)
	(footprint ""
		(layer "F.Cu")
		(at 458.9399 -49.596294 90)
		(property "Reference" "C490"
			(at 0 0 90)
			(layer "F.SilkS")
			(hide yes)
			(effects
				(font
					(size 1.27 1.27)
				)
			)
		)
		(property "Value" "SCD033U25V2KX-GP"
			(at 1.1811 -2.7051 90)
			(unlocked yes)
			(layer "F.Fab")
			(hide yes)
			(effects
				(font
					(size 1.016 1.016)
					(thickness 0.1524)
				)
			)
		)
		(property "Device Type" "C402H22"
			(at 1.1811 -4.2291 90)
			(unlocked yes)
			(layer "F.Fab")
			(hide yes)
			(effects
				(font
					(size 1.016 1.016)
					(thickness 0.1524)
				)
			)
		)
		(duplicate_pad_numbers_are_jumpers no)
		(fp_rect
			(start -0.4318 0.9525)
			(end 0.4318 -0.9525)
			(stroke
				(width 0)
				(type default)
			)
			(fill no)
			(layer "F.CrtYd")
		)
		(fp_rect
			(start -0.4318 0.9525)
			(end 0.4318 -0.9525)
			(stroke
				(width 0)
				(type default)
			)
			(fill no)
			(layer "F.Fab")
		)
		(pad "1" smd custom
			(at 0 -0.4445 90)
			(size 0.1524 0.1524)
			(layers "F.Cu" "F.Mask" "F.Paste")
			(net "SW_HDD_P34")
			(options
				(clearance outline)
				(anchor circle)
			)
			(primitives
				(gr_poly
					(pts
						(arc
							(start 0.3048 -0.2032)
							(mid 0.275042 -0.275042)
							(end 0.2032 -0.3048)
						)
						(arc
							(start -0.2032 -0.3048)
							(mid -0.275042 -0.275042)
							(end -0.3048 -0.2032)
						)
						(arc
							(start -0.3048 0.2032)
							(mid -0.275042 0.275042)
							(end -0.2032 0.3048)
						)
						(arc
							(start 0.2032 0.3048)
							(mid 0.275042 0.275042)
							(end 0.3048 0.2032)
						)
					)
					(width 0)
					(fill yes)
				)
			)
		)
		(pad "2" smd custom
			(at 0 0.4445 90)
			(size 0.1524 0.1524)
			(layers "F.Cu" "F.Mask" "F.Paste")
			(net "GND")
			(options
				(clearance outline)
				(anchor circle)
			)
			(primitives
				(gr_poly
					(pts
						(arc
							(start 0.3048 -0.2032)
							(mid 0.275042 -0.275042)
							(end 0.2032 -0.3048)
						)
						(arc
							(start -0.2032 -0.3048)
							(mid -0.275042 -0.275042)
							(end -0.3048 -0.2032)
						)
						(arc
							(start -0.3048 0.2032)
							(mid -0.275042 0.275042)
							(end -0.2032 0.3048)
						)
						(arc
							(start 0.2032 0.3048)
							(mid 0.275042 0.275042)
							(end 0.3048 0.2032)
						)
					)
					(width 0)
					(fill yes)
				)
			)
		)
	)
	(footprint ""
		(layer "F.Cu")
		(at 458.838808 -242.78844 180)
		(property "Reference" "Q238"
			(at 0 0 180)
			(layer "F.SilkS")
			(hide yes)
			(effects
				(font
					(size 1.27 1.27)
				)
			)
		)
		(property "Value" "2N7002K-2-GP"
			(at 0.127 -8.9662 180)
			(unlocked yes)
			(layer "F.Fab")
			(hide yes)
			(effects
				(font
					(size 1.016 1.016)
					(thickness 0.1524)
				)
			)
		)
		(property "Device Type" "SOT23DGS2D4H44"
			(at 0.127 -10.4902 180)
			(unlocked yes)
			(layer "F.Fab")
			(hide yes)
			(effects
				(font
					(size 1.016 1.016)
					(thickness 0.1524)
				)
			)
		)
		(duplicate_pad_numbers_are_jumpers no)
		(fp_line
			(start 1.651 1.778)
			(end 1.651 -1.778)
			(stroke
				(width 0.1524)
				(type default)
			)
			(layer "F.SilkS")
		)
		(fp_line
			(start 1.651 -1.778)
			(end -1.651 -1.778)
			(stroke
				(width 0.1524)
				(type default)
			)
			(layer "F.SilkS")
		)
		(fp_line
			(start -1.651 1.778)
			(end 1.651 1.778)
			(stroke
				(width 0.1524)
				(type default)
			)
			(layer "F.SilkS")
		)
		(fp_line
			(start -1.651 -1.778)
			(end -1.651 1.778)
			(stroke
				(width 0.1524)
				(type default)
			)
			(layer "F.SilkS")
		)
		(fp_poly
			(pts
				(xy -1.778 1.8796) (xy -1.778 -1.8796) (xy 1.778 -1.8796) (xy 1.778 1.8796)
			)
			(stroke
				(width 0)
				(type default)
			)
			(fill no)
			(layer "F.CrtYd")
		)
		(fp_poly
			(pts
				(xy -1.778 1.8796) (xy -1.778 -1.8796) (xy 1.778 -1.8796) (xy 1.778 1.8796)
			)
			(stroke
				(width 0)
				(type default)
			)
			(fill no)
			(layer "F.Fab")
		)
		(pad "D" smd custom
			(at 0 -0.9525 180)
			(size 0.1905 0.1905)
			(layers "F.Cu" "F.Mask" "F.Paste")
			(net "FLT_HDD11_N")
			(options
				(clearance outline)
				(anchor circle)
			)
			(primitives
				(gr_poly
					(pts
						(arc
							(start -0.1778 0.5715)
							(mid -0.321484 0.511984)
							(end -0.381 0.3683)
						)
						(arc
							(start -0.381 -0.3683)
							(mid -0.321484 -0.511984)
							(end -0.1778 -0.5715)
						)
						(arc
							(start 0.1778 -0.5715)
							(mid 0.321484 -0.511984)
							(end 0.381 -0.3683)
						)
						(arc
							(start 0.381 0.3683)
							(mid 0.321484 0.511984)
							(end 0.1778 0.5715)
						)
					)
					(width 0)
					(fill yes)
				)
			)
		)
		(pad "G" smd custom
			(at -0.98425 0.9525 180)
			(size 0.1905 0.1905)
			(layers "F.Cu" "F.Mask" "F.Paste")
			(net "DRIVE_A_11_FLT_LED")
			(options
				(clearance outline)
				(anchor circle)
			)
			(primitives
				(gr_poly
					(pts
						(arc
							(start -0.1778 0.5715)
							(mid -0.321484 0.511984)
							(end -0.381 0.3683)
						)
						(arc
							(start -0.381 -0.3683)
							(mid -0.321484 -0.511984)
							(end -0.1778 -0.5715)
						)
						(arc
							(start 0.1778 -0.5715)
							(mid 0.321484 -0.511984)
							(end 0.381 -0.3683)
						)
						(arc
							(start 0.381 0.3683)
							(mid 0.321484 0.511984)
							(end 0.1778 0.5715)
						)
					)
					(width 0)
					(fill yes)
				)
			)
		)
		(pad "S" smd custom
			(at 0.98425 0.9525 180)
			(size 0.1905 0.1905)
			(layers "F.Cu" "F.Mask" "F.Paste")
			(net "GND")
			(options
				(clearance outline)
				(anchor circle)
			)
			(primitives
				(gr_poly
					(pts
						(arc
							(start -0.1778 0.5715)
							(mid -0.321484 0.511984)
							(end -0.381 0.3683)
						)
						(arc
							(start -0.381 -0.3683)
							(mid -0.321484 -0.511984)
							(end -0.1778 -0.5715)
						)
						(arc
							(start 0.1778 -0.5715)
							(mid 0.321484 -0.511984)
							(end 0.381 -0.3683)
						)
						(arc
							(start 0.381 0.3683)
							(mid 0.321484 0.511984)
							(end 0.1778 0.5715)
						)
					)
					(width 0)
					(fill yes)
				)
			)
		)
	)
	(footprint ""
		(layer "F.Cu")
		(at 54.546246 -160.887918 90)
		(property "Reference" "R441"
			(at 0 0 90)
			(layer "F.SilkS")
			(hide yes)
			(effects
				(font
					(size 1.27 1.27)
				)
			)
		)
		(property "Value" "4K7R2J-2-GP"
			(at 0.064008 -3.993896 90)
			(unlocked yes)
			(layer "F.Fab")
			(hide yes)
			(effects
				(font
					(size 1.016 1.016)
					(thickness 0.1524)
				)
			)
		)
		(property "Device Type" "R402H16"
			(at 0.064008 -5.517896 90)
			(unlocked yes)
			(layer "F.Fab")
			(hide yes)
			(effects
				(font
					(size 1.016 1.016)
					(thickness 0.1524)
				)
			)
		)
		(duplicate_pad_numbers_are_jumpers no)
		(fp_line
			(start 0.508 -0.9398)
			(end -0.508 -0.9398)
			(stroke
				(width 0.1524)
				(type default)
			)
			(layer "F.SilkS")
		)
		(fp_line
			(start -0.508 -0.9398)
			(end -0.508 0.9398)
			(stroke
				(width 0.1524)
				(type default)
			)
			(layer "F.SilkS")
		)
		(fp_rect
			(start -0.508 0.9398)
			(end 0.508 -0.9398)
			(stroke
				(width 0)
				(type default)
			)
			(fill no)
			(layer "F.CrtYd")
		)
		(fp_rect
			(start -0.508 0.9398)
			(end 0.508 -0.9398)
			(stroke
				(width 0)
				(type default)
			)
			(fill no)
			(layer "F.Fab")
		)
		(pad "1" smd custom
			(at 0 -0.4445 90)
			(size 0.1397 0.1397)
			(layers "F.Cu" "F.Mask" "F.Paste")
			(net "SW_PWR_R_HDD13")
			(options
				(clearance outline)
				(anchor circle)
			)
			(primitives
				(gr_poly
					(pts
						(arc
							(start -0.1778 -0.2794)
							(mid -0.249642 -0.249642)
							(end -0.2794 -0.1778)
						)
						(arc
							(start -0.2794 0.1778)
							(mid -0.249642 0.249642)
							(end -0.1778 0.2794)
						)
						(arc
							(start 0.1778 0.2794)
							(mid 0.249642 0.249642)
							(end 0.2794 0.1778)
						)
						(arc
							(start 0.2794 -0.1778)
							(mid 0.249642 -0.249642)
							(end 0.1778 -0.2794)
						)
					)
					(width 0)
					(fill yes)
				)
			)
		)
		(pad "2" smd custom
			(at 0 0.4445 90)
			(size 0.1397 0.1397)
			(layers "F.Cu" "F.Mask" "F.Paste")
			(net "GND")
			(options
				(clearance outline)
				(anchor circle)
			)
			(primitives
				(gr_poly
					(pts
						(arc
							(start -0.1778 -0.2794)
							(mid -0.249642 -0.249642)
							(end -0.2794 -0.1778)
						)
						(arc
							(start -0.2794 0.1778)
							(mid -0.249642 0.249642)
							(end -0.1778 0.2794)
						)
						(arc
							(start 0.1778 0.2794)
							(mid 0.249642 0.249642)
							(end 0.2794 0.1778)
						)
						(arc
							(start 0.2794 -0.1778)
							(mid 0.249642 -0.249642)
							(end 0.1778 -0.2794)
						)
					)
					(width 0)
					(fill yes)
				)
			)
		)
	)
	(footprint ""
		(layer "F.Cu")
		(at 432.724052 -49.443894 90)
		(property "Reference" "R905"
			(at 0 0 90)
			(layer "F.SilkS")
			(hide yes)
			(effects
				(font
					(size 1.27 1.27)
				)
			)
		)
		(property "Value" "200KR2F-L-GP"
			(at 0.064008 -3.993896 90)
			(unlocked yes)
			(layer "F.Fab")
			(hide yes)
			(effects
				(font
					(size 1.016 1.016)
					(thickness 0.1524)
				)
			)
		)
		(property "Device Type" "R402H16"
			(at 0.064008 -5.517896 90)
			(unlocked yes)
			(layer "F.Fab")
			(hide yes)
			(effects
				(font
					(size 1.016 1.016)
					(thickness 0.1524)
				)
			)
		)
		(duplicate_pad_numbers_are_jumpers no)
		(fp_line
			(start 0.508 -0.9398)
			(end -0.508 -0.9398)
			(stroke
				(width 0.1524)
				(type default)
			)
			(layer "F.SilkS")
		)
		(fp_line
			(start -0.508 -0.9398)
			(end -0.508 0.9398)
			(stroke
				(width 0.1524)
				(type default)
			)
			(layer "F.SilkS")
		)
		(fp_rect
			(start -0.508 0.9398)
			(end 0.508 -0.9398)
			(stroke
				(width 0)
				(type default)
			)
			(fill no)
			(layer "F.CrtYd")
		)
		(fp_rect
			(start -0.508 0.9398)
			(end 0.508 -0.9398)
			(stroke
				(width 0)
				(type default)
			)
			(fill no)
			(layer "F.Fab")
		)
		(pad "1" smd custom
			(at 0 -0.4445 90)
			(size 0.1397 0.1397)
			(layers "F.Cu" "F.Mask" "F.Paste")
			(net "SW_HDD_R33")
			(options
				(clearance outline)
				(anchor circle)
			)
			(primitives
				(gr_poly
					(pts
						(arc
							(start -0.1778 -0.2794)
							(mid -0.249642 -0.249642)
							(end -0.2794 -0.1778)
						)
						(arc
							(start -0.2794 0.1778)
							(mid -0.249642 0.249642)
							(end -0.1778 0.2794)
						)
						(arc
							(start 0.1778 0.2794)
							(mid 0.249642 0.249642)
							(end 0.2794 0.1778)
						)
						(arc
							(start 0.2794 -0.1778)
							(mid 0.249642 -0.249642)
							(end 0.1778 -0.2794)
						)
					)
					(width 0)
					(fill yes)
				)
			)
		)
		(pad "2" smd custom
			(at 0 0.4445 90)
			(size 0.1397 0.1397)
			(layers "F.Cu" "F.Mask" "F.Paste")
			(net "SW_HDD_N33")
			(options
				(clearance outline)
				(anchor circle)
			)
			(primitives
				(gr_poly
					(pts
						(arc
							(start -0.1778 -0.2794)
							(mid -0.249642 -0.249642)
							(end -0.2794 -0.1778)
						)
						(arc
							(start -0.2794 0.1778)
							(mid -0.249642 0.249642)
							(end -0.1778 0.2794)
						)
						(arc
							(start 0.1778 0.2794)
							(mid 0.249642 0.249642)
							(end 0.2794 0.1778)
						)
						(arc
							(start 0.2794 -0.1778)
							(mid 0.249642 -0.249642)
							(end 0.1778 -0.2794)
						)
					)
					(width 0)
					(fill yes)
				)
			)
		)
	)
)
